# S9S_MB_2U (Grand Teton) — schematic netlist excerpt (pin names and nets, part order shuffled) for the footprints in the layout excerpt that follows; sources: Cadence DE-HDL packaged netlist, KiCad conversion of 03242023_DA0F0TMBIJ0_F0T_Motherboard_J_brd_V01_OCP.brd

R111  Q_RES  10K 1% CHIP  pkg 0402LF  page 223 : A = P3V3 ; B = FM_PLD_CLKS_OE_R_N
R1814  Q_RES  1K 1% EMPTY  pkg 0402LF  page 239 : A = FM_JTAG_BMC_MUX_SEL ; B = GND

(kicad_pcb
	(version 20260206)
	(generator "pcbnew")
	(generator_version "10.0")
	(general
		(thickness 1.6)
		(legacy_teardrops no)
	)
	(paper "A4")
	(title_block
		(title "03242023_DA0F0TMBIJ0_F0T_Motherboard_J_brd_V01_OCP.brd")
		(comment 1 "Grand Teton / footprints 3395-3396 of 6105")
	)
	(layers
		(0 "F.Cu" signal "TOP")
		(4 "In1.Cu" signal "GND")
		(6 "In2.Cu" signal "IN1")
		(8 "In3.Cu" signal "GND1")
		(10 "In4.Cu" signal "IN2")
		(12 "In5.Cu" signal "GND2")
		(14 "In6.Cu" signal "IN3")
		(16 "In7.Cu" signal "GND3")
		(18 "In8.Cu" signal "VCC")
		(20 "In9.Cu" signal "VCC1")
		(22 "In10.Cu" signal "GND4")
		(24 "In11.Cu" signal "IN4")
		(26 "In12.Cu" signal "GND5")
		(28 "In13.Cu" signal "IN5")
		(30 "In14.Cu" signal "GND6")
		(32 "In15.Cu" signal "IN6")
		(34 "In16.Cu" signal "GND7")
		(2 "B.Cu" signal "BOTTOM")
		(9 "F.Adhes" user "F.Adhesive")
		(11 "B.Adhes" user "B.Adhesive")
		(13 "F.Paste" user "Package Geometry/Pastemask Top")
		(15 "B.Paste" user "Package Geometry/Pastemask Bottom")
		(5 "F.SilkS" user "Ref Des/Silkscreen Top")
		(7 "B.SilkS" user "Ref Des/Silkscreen Bottom")
		(1 "F.Mask" user "Board Geometry/Soldermask Top")
		(3 "B.Mask" user "Board Geometry/Soldermask Bottom")
		(17 "Dwgs.User" user "User.Drawings")
		(19 "Cmts.User" user "User.Comments")
		(21 "Eco1.User" user "User.Eco1")
		(23 "Eco2.User" user "User.Eco2")
		(25 "Edge.Cuts" user "Board Geometry/Outline")
		(27 "Margin" user)
		(31 "F.CrtYd" user "Package Geometry/Place Bound Top")
		(29 "B.CrtYd" user "Package Geometry/Place Bound Bottom")
		(35 "F.Fab" user "Ref Des/Assembly Top")
		(33 "B.Fab" user "Ref Des/Assembly Bottom")
	)
	(footprint ""
		(layer "F.Cu")
		(at 124.672344 -78.587092 180)
		(property "Reference" "R1814"
			(at 0 0 180)
			(layer "F.SilkS")
			(hide yes)
			(effects
				(font
					(size 1.27 1.27)
				)
			)
		)
		(property "Value" ""
			(at 0 0 180)
			(layer "F.Fab")
			(effects
				(font
					(size 1.27 1.27)
				)
			)
		)
		(duplicate_pad_numbers_are_jumpers no)
		(fp_line
			(start 0.7874 0.4064)
			(end -0.7874 0.4064)
			(stroke
				(width 0.1524)
				(type default)
			)
			(layer "F.SilkS")
		)
		(fp_line
			(start 0.7874 -0.4064)
			(end 0.7874 0.4064)
			(stroke
				(width 0.1524)
				(type default)
			)
			(layer "F.SilkS")
		)
		(fp_line
			(start -0.7874 0.4064)
			(end -0.7874 -0.4064)
			(stroke
				(width 0.1524)
				(type default)
			)
			(layer "F.SilkS")
		)
		(fp_line
			(start -0.7874 -0.4064)
			(end 0.7874 -0.4064)
			(stroke
				(width 0.1524)
				(type default)
			)
			(layer "F.SilkS")
		)
		(fp_line
			(start 0.67945 0.3048)
			(end 0.120396 0.3048)
			(stroke
				(width 0.1)
				(type default)
			)
			(layer "F.Fab")
		)
		(fp_line
			(start 0.67945 -0.3048)
			(end 0.67945 0.3048)
			(stroke
				(width 0.1)
				(type default)
			)
			(layer "F.Fab")
		)
		(fp_line
			(start 0.12065 -0.2794)
			(end 0.12065 -0.3048)
			(stroke
				(width 0.1)
				(type default)
			)
			(layer "F.Fab")
		)
		(fp_line
			(start 0.12065 -0.3048)
			(end 0.67945 -0.3048)
			(stroke
				(width 0.1)
				(type default)
			)
			(layer "F.Fab")
		)
		(fp_line
			(start 0.120396 0.3048)
			(end 0.120396 0.2794)
			(stroke
				(width 0.1)
				(type default)
			)
			(layer "F.Fab")
		)
		(fp_line
			(start 0.120396 0.2794)
			(end -0.12065 0.2794)
			(stroke
				(width 0.1)
				(type default)
			)
			(layer "F.Fab")
		)
		(fp_line
			(start -0.12065 0.3048)
			(end -0.67945 0.3048)
			(stroke
				(width 0.1)
				(type default)
			)
			(layer "F.Fab")
		)
		(fp_line
			(start -0.12065 0.2794)
			(end -0.12065 0.3048)
			(stroke
				(width 0.1)
				(type default)
			)
			(layer "F.Fab")
		)
		(fp_line
			(start -0.12065 -0.2794)
			(end 0.12065 -0.2794)
			(stroke
				(width 0.1)
				(type default)
			)
			(layer "F.Fab")
		)
		(fp_line
			(start -0.12065 -0.305054)
			(end -0.12065 -0.2794)
			(stroke
				(width 0.1)
				(type default)
			)
			(layer "F.Fab")
		)
		(fp_line
			(start -0.67945 0.3048)
			(end -0.67945 -0.305054)
			(stroke
				(width 0.1)
				(type default)
			)
			(layer "F.Fab")
		)
		(fp_line
			(start -0.67945 -0.305054)
			(end -0.12065 -0.305054)
			(stroke
				(width 0.1)
				(type default)
			)
			(layer "F.Fab")
		)
		(pad "1" smd circle
			(at -0.40005 0 180)
			(size 0 0)
			(layers "F.Cu" "F.Mask" "F.Paste")
			(net "FM_JTAG_BMC_MUX_SEL")
		)
		(pad "2" smd circle
			(at 0.40005 0 180)
			(size 0 0)
			(layers "F.Cu" "F.Mask" "F.Paste")
			(net "GND")
		)
	)
	(footprint ""
		(layer "F.Cu")
		(at 272.07337 -98.227642 180)
		(property "Reference" "R111"
			(at 0 0 180)
			(layer "F.SilkS")
			(hide yes)
			(effects
				(font
					(size 1.27 1.27)
				)
			)
		)
		(property "Value" ""
			(at 0 0 180)
			(layer "F.Fab")
			(effects
				(font
					(size 1.27 1.27)
				)
			)
		)
		(duplicate_pad_numbers_are_jumpers no)
		(fp_line
			(start 0.7874 0.4064)
			(end -0.7874 0.4064)
			(stroke
				(width 0.1524)
				(type default)
			)
			(layer "F.SilkS")
		)
		(fp_line
			(start 0.7874 -0.4064)
			(end 0.7874 0.4064)
			(stroke
				(width 0.1524)
				(type default)
			)
			(layer "F.SilkS")
		)
		(fp_line
			(start -0.7874 0.4064)
			(end -0.7874 -0.4064)
			(stroke
				(width 0.1524)
				(type default)
			)
			(layer "F.SilkS")
		)
		(fp_line
			(start -0.7874 -0.4064)
			(end 0.7874 -0.4064)
			(stroke
				(width 0.1524)
				(type default)
			)
			(layer "F.SilkS")
		)
		(fp_line
			(start 0.67945 0.3048)
			(end 0.120396 0.3048)
			(stroke
				(width 0.1)
				(type default)
			)
			(layer "F.Fab")
		)
		(fp_line
			(start 0.67945 -0.3048)
			(end 0.67945 0.3048)
			(stroke
				(width 0.1)
				(type default)
			)
			(layer "F.Fab")
		)
		(fp_line
			(start 0.12065 -0.2794)
			(end 0.12065 -0.3048)
			(stroke
				(width 0.1)
				(type default)
			)
			(layer "F.Fab")
		)
		(fp_line
			(start 0.12065 -0.3048)
			(end 0.67945 -0.3048)
			(stroke
				(width 0.1)
				(type default)
			)
			(layer "F.Fab")
		)
		(fp_line
			(start 0.120396 0.3048)
			(end 0.120396 0.2794)
			(stroke
				(width 0.1)
				(type default)
			)
			(layer "F.Fab")
		)
		(fp_line
			(start 0.120396 0.2794)
			(end -0.12065 0.2794)
			(stroke
				(width 0.1)
				(type default)
			)
			(layer "F.Fab")
		)
		(fp_line
			(start -0.12065 0.3048)
			(end -0.67945 0.3048)
			(stroke
				(width 0.1)
				(type default)
			)
			(layer "F.Fab")
		)
		(fp_line
			(start -0.12065 0.2794)
			(end -0.12065 0.3048)
			(stroke
				(width 0.1)
				(type default)
			)
			(layer "F.Fab")
		)
		(fp_line
			(start -0.12065 -0.2794)
			(end 0.12065 -0.2794)
			(stroke
				(width 0.1)
				(type default)
			)
			(layer "F.Fab")
		)
		(fp_line
			(start -0.12065 -0.305054)
			(end -0.12065 -0.2794)
			(stroke
				(width 0.1)
				(type default)
			)
			(layer "F.Fab")
		)
		(fp_line
			(start -0.67945 0.3048)
			(end -0.67945 -0.305054)
			(stroke
				(width 0.1)
				(type default)
			)
			(layer "F.Fab")
		)
		(fp_line
			(start -0.67945 -0.305054)
			(end -0.12065 -0.305054)
			(stroke
				(width 0.1)
				(type default)
			)
			(layer "F.Fab")
		)
		(pad "1" smd circle
			(at -0.40005 0 180)
			(size 0 0)
			(layers "F.Cu" "F.Mask" "F.Paste")
			(net "P3V3")
		)
		(pad "2" smd circle
			(at 0.40005 0 180)
			(size 0 0)
			(layers "F.Cu" "F.Mask" "F.Paste")
			(net "FM_PLD_CLKS_OE_R_N")
		)
	)
)
